(kicad_pcb
	(version 20260206)
	(generator "pcbnew")
	(generator_version "10.0")
	(general
		(thickness 1.6)
		(legacy_teardrops no)
	)
	(paper "A4")
	(title_block
		(title "Wiwynn_Tioga_Pass_MB.brd")
		(comment 1 "Tioga Pass / footprint 190 of 4770 (U2D1), pads 1753-1862 of 3647")
	)
	(layers
		(0 "F.Cu" signal "TOP")
		(4 "In1.Cu" signal "L2GND")
		(6 "In2.Cu" signal "L3")
		(8 "In3.Cu" signal "L4GND")
		(10 "In4.Cu" signal "L5")
		(12 "In5.Cu" signal "L6GND")
		(14 "In6.Cu" signal "L7VCC")
		(16 "In7.Cu" signal "L8VCC")
		(18 "In8.Cu" signal "L9GND")
		(20 "In9.Cu" signal "L10")
		(22 "In10.Cu" signal "L11GND")
		(24 "In11.Cu" signal "L12")
		(26 "In12.Cu" signal "L13GND")
		(2 "B.Cu" signal "BOTTOM")
		(9 "F.Adhes" user "F.Adhesive")
		(11 "B.Adhes" user "B.Adhesive")
		(13 "F.Paste" user "Package Geometry/Pastemask Top")
		(15 "B.Paste" user "Package Geometry/Pastemask Bottom")
		(5 "F.SilkS" user "Ref Des/Silkscreen Top")
		(7 "B.SilkS" user "Ref Des/Silkscreen Bottom")
		(1 "F.Mask" user "Board Geometry/Soldermask Top")
		(3 "B.Mask" user "Board Geometry/Soldermask Bottom")
		(17 "Dwgs.User" user "User.Drawings")
		(19 "Cmts.User" user "User.Comments")
		(21 "Eco1.User" user "User.Eco1")
		(23 "Eco2.User" user "User.Eco2")
		(25 "Edge.Cuts" user "Board Geometry/Outline")
		(27 "Margin" user)
		(31 "F.CrtYd" user "Package Geometry/Place Bound Top")
		(29 "B.CrtYd" user "Package Geometry/Place Bound Bottom")
		(35 "F.Fab" user "Ref Des/Assembly Top")
		(33 "B.Fab" user "Ref Des/Assembly Bottom")
	)
	(footprint ""
		(layer "F.Cu")
		(at 104.99979 -76.550012 180)
		(property "Reference" "U2D1"
			(at 25.19299 30.484318 0)
			(unlocked yes)
			(layer "F.SilkS")
			(effects
				(font
					(size 0.7874 0.5842)
					(thickness 0.1524)
				)
			)
		)
		(property "Value" ""
			(at 0 0 180)
			(layer "F.Fab")
			(effects
				(font
					(size 1.27 1.27)
				)
			)
		)
		(duplicate_pad_numbers_are_jumpers no)
		(pad "CU10" smd circle
			(at -29.523944 12.539726)
			(size 0.4318 0.4318)
			(layers "F.Cu" "F.Mask" "F.Paste")
			(net "P3E_CPU1_PE3_MP_RXP<15>")
		)
		(pad "CU12" smd circle
			(at -27.806904 12.539726)
			(size 0.4318 0.4318)
			(layers "F.Cu" "F.Mask" "F.Paste")
			(net "PVCCIO_CPU1")
		)
		(pad "CU14" smd circle
			(at -26.090118 12.539726)
			(size 0.4318 0.4318)
			(layers "F.Cu" "F.Mask" "F.Paste")
			(net "TP_CPU1_UPI2_RSVD_DD17")
		)
		(pad "CU18" smd circle
			(at -22.656038 12.539726)
			(size 0.4318 0.4318)
			(layers "F.Cu" "F.Mask" "F.Paste")
			(net "PVCCIO_CPU1")
		)
		(pad "CU20" smd circle
			(at -20.938998 12.539726)
			(size 0.4318 0.4318)
			(layers "F.Cu" "F.Mask" "F.Paste")
			(net "GND")
		)
		(pad "CU22" smd circle
			(at -19.221958 12.539726)
			(size 0.4318 0.4318)
			(layers "F.Cu" "F.Mask" "F.Paste")
			(net "GND")
		)
		(pad "CU24" smd circle
			(at -17.504918 12.539726)
			(size 0.4318 0.4318)
			(layers "F.Cu" "F.Mask" "F.Paste")
			(net "PVCCMCP_CPU1")
		)
		(pad "CU26" smd circle
			(at -15.787878 12.539726)
			(size 0.4318 0.4318)
			(layers "F.Cu" "F.Mask" "F.Paste")
			(net "CLK_100M_CPU1_BCLK2_DP")
		)
		(pad "CU28" smd circle
			(at -14.071092 12.539726)
			(size 0.4318 0.4318)
			(layers "F.Cu" "F.Mask" "F.Paste")
			(net "GND")
		)
		(pad "CU30" smd circle
			(at -12.354052 12.539726)
			(size 0.4318 0.4318)
			(layers "F.Cu" "F.Mask" "F.Paste")
			(net "GND")
		)
		(pad "CU32" smd circle
			(at -10.637012 12.539726)
			(size 0.4318 0.4318)
			(layers "F.Cu" "F.Mask" "F.Paste")
			(net "A_CPU1_MCP01_RBIAS")
		)
		(pad "CU34" smd circle
			(at -8.919972 12.539726)
			(size 0.4318 0.4318)
			(layers "F.Cu" "F.Mask" "F.Paste")
			(net "GND")
		)
		(pad "CU36" smd circle
			(at -7.202932 12.539726)
			(size 0.4318 0.4318)
			(layers "F.Cu" "F.Mask" "F.Paste")
			(net "GND")
		)
		(pad "CU38" smd circle
			(at -5.485892 12.539726)
			(size 0.4318 0.4318)
			(layers "F.Cu" "F.Mask" "F.Paste")
			(net "PVCCIN_CPU1")
		)
		(pad "CU40" smd circle
			(at -3.769106 12.539726)
			(size 0.4318 0.4318)
			(layers "F.Cu" "F.Mask" "F.Paste")
			(net "PVCCIN_CPU1")
		)
		(pad "CU42" smd circle
			(at -2.052066 12.539726)
			(size 0.4318 0.4318)
			(layers "F.Cu" "F.Mask" "F.Paste")
			(net "PVCCIN_CPU1")
		)
		(pad "CU52" smd circle
			(at 8.061452 10.739628)
			(size 0.508 0.508)
			(layers "F.Cu" "F.Mask" "F.Paste")
			(net "PVCCIN_CPU1")
		)
		(pad "CU54" smd circle
			(at 9.778492 10.739628)
			(size 0.4318 0.4318)
			(layers "F.Cu" "F.Mask" "F.Paste")
			(net "PVCCIN_CPU1")
		)
		(pad "CU56" smd circle
			(at 11.495532 10.739628)
			(size 0.4318 0.4318)
			(layers "F.Cu" "F.Mask" "F.Paste")
			(net "GND")
		)
		(pad "CU58" smd circle
			(at 13.212572 10.739628)
			(size 0.4318 0.4318)
			(layers "F.Cu" "F.Mask" "F.Paste")
			(net "PU_PIROM_CPU1_ADDR0")
		)
		(pad "CU60" smd circle
			(at 14.929612 10.739628)
			(size 0.4318 0.4318)
			(layers "F.Cu" "F.Mask" "F.Paste")
			(net "TP_CPU1_RSVD_66")
		)
		(pad "CU62" smd circle
			(at 16.646398 10.739628)
			(size 0.4318 0.4318)
			(layers "F.Cu" "F.Mask" "F.Paste")
			(net "GND")
		)
		(pad "CU64" smd circle
			(at 18.363438 10.739628)
			(size 0.4318 0.4318)
			(layers "F.Cu" "F.Mask" "F.Paste")
			(net "M_M_DQ<31>")
		)
		(pad "CU66" smd circle
			(at 20.080478 10.739628)
			(size 0.4318 0.4318)
			(layers "F.Cu" "F.Mask" "F.Paste")
			(net "M_M_DQ<25>")
		)
		(pad "CU68" smd circle
			(at 21.797518 10.739628)
			(size 0.4318 0.4318)
			(layers "F.Cu" "F.Mask" "F.Paste")
			(net "GND")
		)
		(pad "CU74" smd circle
			(at 26.948384 10.739628)
			(size 0.4318 0.4318)
			(layers "F.Cu" "F.Mask" "F.Paste")
			(net "M_M_DQS_DP<9>")
		)
		(pad "CU76" smd circle
			(at 28.665424 10.739628)
			(size 0.4318 0.4318)
			(layers "F.Cu" "F.Mask" "F.Paste")
			(net "GND")
		)
		(pad "CU78" smd circle
			(at 30.382464 10.739628)
			(size 0.4318 0.4318)
			(layers "F.Cu" "F.Mask" "F.Paste")
			(net "GND")
		)
		(pad "CU80" smd circle
			(at 32.099504 10.739628)
			(size 0.4318 0.4318)
			(layers "F.Cu" "F.Mask" "F.Paste")
			(net "GND")
		)
		(pad "CU82" smd circle
			(at 33.816544 10.739628)
			(size 0.4318 0.4318)
			(layers "F.Cu" "F.Mask" "F.Paste")
			(net "GND")
		)
		(pad "CU84" smd circle
			(at 35.533584 10.739628)
			(size 0.4318 0.4318)
			(layers "F.Cu" "F.Mask" "F.Paste")
			(net "M_K_DQS_DN<0>")
		)
		(pad "CU86" smd custom
			(at 37.250624 10.739628 270)
			(size 0.10795 0.10795)
			(layers "F.Cu" "F.Mask" "F.Paste")
			(net "GND")
			(options
				(clearance outline)
				(anchor circle)
			)
			(primitives
				(gr_poly
					(pts
						(arc
							(start 0.2159 -0.0381)
							(mid 0 -0.254)
							(end -0.2159 -0.0381)
						)
						(arc
							(start -0.2159 0.0381)
							(mid 0 0.254)
							(end 0.2159 0.0381)
						)
					)
					(width 0)
					(fill yes)
				)
			)
		)
		(pad "CV1" smd custom
			(at -37.250624 13.034772 90)
			(size 0.10795 0.10795)
			(layers "F.Cu" "F.Mask" "F.Paste")
			(net "GND")
			(options
				(clearance outline)
				(anchor circle)
			)
			(primitives
				(gr_poly
					(pts
						(arc
							(start 0.2159 -0.0381)
							(mid 0 -0.254)
							(end -0.2159 -0.0381)
						)
						(arc
							(start -0.2159 0.0381)
							(mid 0 0.254)
							(end 0.2159 0.0381)
						)
					)
					(width 0)
					(fill yes)
				)
			)
		)
		(pad "CV3" smd circle
			(at -35.533584 13.034772)
			(size 0.4318 0.4318)
			(layers "F.Cu" "F.Mask" "F.Paste")
			(net "TP_P3E_CPU1_PE2_RSR_TXN<1>")
		)
		(pad "CV5" smd circle
			(at -33.816544 13.034772)
			(size 0.4318 0.4318)
			(layers "F.Cu" "F.Mask" "F.Paste")
			(net "P3E_CPU1_PE3_MP_TXP<15>")
		)
		(pad "CV7" smd circle
			(at -32.099504 13.034772)
			(size 0.4318 0.4318)
			(layers "F.Cu" "F.Mask" "F.Paste")
			(net "PVCCIO_CPU1")
		)
		(pad "CV9" smd circle
			(at -30.382464 13.034772)
			(size 0.4318 0.4318)
			(layers "F.Cu" "F.Mask" "F.Paste")
			(net "P3E_CPU1_PE3_MP_RXN<15>")
		)
		(pad "CV11" smd circle
			(at -28.665424 13.034772)
			(size 0.4318 0.4318)
			(layers "F.Cu" "F.Mask" "F.Paste")
			(net "TP_CPU1_DMI_RX_DP3")
		)
		(pad "CV13" smd circle
			(at -26.948384 13.034772)
			(size 0.4318 0.4318)
			(layers "F.Cu" "F.Mask" "F.Paste")
			(net "TP_CPU1_UPI2_RSVD_DD15")
		)
		(pad "CV17" smd circle
			(at -23.514558 13.034772)
			(size 0.4318 0.4318)
			(layers "F.Cu" "F.Mask" "F.Paste")
			(net "GND")
		)
		(pad "CV19" smd circle
			(at -21.797518 13.034772)
			(size 0.4318 0.4318)
			(layers "F.Cu" "F.Mask" "F.Paste")
			(net "GND")
		)
		(pad "CV21" smd circle
			(at -20.080478 13.034772)
			(size 0.4318 0.4318)
			(layers "F.Cu" "F.Mask" "F.Paste")
			(net "PVCCIO_CPU1")
		)
		(pad "CV23" smd circle
			(at -18.363438 13.034772)
			(size 0.4318 0.4318)
			(layers "F.Cu" "F.Mask" "F.Paste")
			(net "PVCCMCP_CPU1")
		)
		(pad "CV25" smd circle
			(at -16.646398 13.034772)
			(size 0.4318 0.4318)
			(layers "F.Cu" "F.Mask" "F.Paste")
			(net "GND")
		)
		(pad "CV27" smd circle
			(at -14.929612 13.034772)
			(size 0.4318 0.4318)
			(layers "F.Cu" "F.Mask" "F.Paste")
			(net "GND")
		)
		(pad "CV29" smd circle
			(at -13.212572 13.034772)
			(size 0.4318 0.4318)
			(layers "F.Cu" "F.Mask" "F.Paste")
			(net "M_M_DQS_DP<16>")
		)
		(pad "CV31" smd circle
			(at -11.495532 13.034772)
			(size 0.4318 0.4318)
			(layers "F.Cu" "F.Mask" "F.Paste")
			(net "GND")
		)
		(pad "CV33" smd circle
			(at -9.778492 13.034772)
			(size 0.4318 0.4318)
			(layers "F.Cu" "F.Mask" "F.Paste")
			(net "GND")
		)
		(pad "CV35" smd circle
			(at -8.061452 13.034772)
			(size 0.4318 0.4318)
			(layers "F.Cu" "F.Mask" "F.Paste")
			(net "M_M_DQS_DP<15>")
		)
		(pad "CV37" smd circle
			(at -6.344412 13.034772)
			(size 0.4318 0.4318)
			(layers "F.Cu" "F.Mask" "F.Paste")
			(net "GND")
		)
		(pad "CV39" smd circle
			(at -4.627626 13.034772)
			(size 0.4318 0.4318)
			(layers "F.Cu" "F.Mask" "F.Paste")
			(net "GND")
		)
		(pad "CV41" smd circle
			(at -2.910586 13.034772)
			(size 0.4318 0.4318)
			(layers "F.Cu" "F.Mask" "F.Paste")
			(net "GND")
		)
		(pad "CV51" smd circle
			(at 7.202932 11.234674)
			(size 0.508 0.508)
			(layers "F.Cu" "F.Mask" "F.Paste")
			(net "PVCCIN_CPU1")
		)
		(pad "CV53" smd circle
			(at 8.919972 11.234674)
			(size 0.4318 0.4318)
			(layers "F.Cu" "F.Mask" "F.Paste")
			(net "GND")
		)
		(pad "CV55" smd circle
			(at 10.637012 11.234674)
			(size 0.4318 0.4318)
			(layers "F.Cu" "F.Mask" "F.Paste")
			(net "GND")
		)
		(pad "CV57" smd circle
			(at 12.354052 11.234674)
			(size 0.4318 0.4318)
			(layers "F.Cu" "F.Mask" "F.Paste")
			(net "PD_PIROM_CPU1_ADDR1")
		)
		(pad "CV59" smd circle
			(at 14.071092 11.234674)
			(size 0.4318 0.4318)
			(layers "F.Cu" "F.Mask" "F.Paste")
			(net "FM_CPU1_SM_WP")
		)
		(pad "CV61" smd circle
			(at 15.787878 11.234674)
			(size 0.4318 0.4318)
			(layers "F.Cu" "F.Mask" "F.Paste")
			(net "M_M_CPU_VREF")
		)
		(pad "CV63" smd circle
			(at 17.504918 11.234674)
			(size 0.4318 0.4318)
			(layers "F.Cu" "F.Mask" "F.Paste")
			(net "GND")
		)
		(pad "CV65" smd circle
			(at 19.221958 11.234674)
			(size 0.4318 0.4318)
			(layers "F.Cu" "F.Mask" "F.Paste")
			(net "M_M_DQS_DN<3>")
		)
		(pad "CV67" smd circle
			(at 20.938998 11.234674)
			(size 0.4318 0.4318)
			(layers "F.Cu" "F.Mask" "F.Paste")
			(net "GND")
		)
		(pad "CV69" smd circle
			(at 22.656038 11.234674)
			(size 0.4318 0.4318)
			(layers "F.Cu" "F.Mask" "F.Paste")
			(net "TP_CPU1_RSVD_64")
		)
		(pad "CV73" smd circle
			(at 26.090118 11.234674)
			(size 0.4318 0.4318)
			(layers "F.Cu" "F.Mask" "F.Paste")
			(net "GND")
		)
		(pad "CV75" smd circle
			(at 27.806904 11.234674)
			(size 0.4318 0.4318)
			(layers "F.Cu" "F.Mask" "F.Paste")
			(net "M_M_DQ<6>")
		)
		(pad "CV77" smd circle
			(at 29.523944 11.234674)
			(size 0.4318 0.4318)
			(layers "F.Cu" "F.Mask" "F.Paste")
			(net "M_M_DQ<3>")
		)
		(pad "CV79" smd circle
			(at 31.240984 11.234674)
			(size 0.4318 0.4318)
			(layers "F.Cu" "F.Mask" "F.Paste")
			(net "GND")
		)
		(pad "CV81" smd circle
			(at 32.958024 11.234674)
			(size 0.4318 0.4318)
			(layers "F.Cu" "F.Mask" "F.Paste")
			(net "GND")
		)
		(pad "CV83" smd circle
			(at 34.675064 11.234674)
			(size 0.4318 0.4318)
			(layers "F.Cu" "F.Mask" "F.Paste")
			(net "GND")
		)
		(pad "CV85" smd circle
			(at 36.392104 11.234674)
			(size 0.4318 0.4318)
			(layers "F.Cu" "F.Mask" "F.Paste")
			(net "M_K_DQS_DP<0>")
		)
		(pad "CW2" smd circle
			(at -36.392104 13.530326)
			(size 0.4318 0.4318)
			(layers "F.Cu" "F.Mask" "F.Paste")
			(net "TP_P3E_CPU1_PE1_MP_TXP<0>")
		)
		(pad "CW4" smd circle
			(at -34.675064 13.530326)
			(size 0.4318 0.4318)
			(layers "F.Cu" "F.Mask" "F.Paste")
			(net "TP_P3E_CPU1_PE2_RSR_TXP<0>")
		)
		(pad "CW6" smd circle
			(at -32.958024 13.530326)
			(size 0.4318 0.4318)
			(layers "F.Cu" "F.Mask" "F.Paste")
			(net "GND")
		)
		(pad "CW8" smd circle
			(at -31.240984 13.530326)
			(size 0.4318 0.4318)
			(layers "F.Cu" "F.Mask" "F.Paste")
			(net "TP_P3E_CPU1_PE1_MP_RXN<0>")
		)
		(pad "CW10" smd circle
			(at -29.523944 13.530326)
			(size 0.4318 0.4318)
			(layers "F.Cu" "F.Mask" "F.Paste")
			(net "P3E_CPU1_PE3_MP_RXP<14>")
		)
		(pad "CW12" smd circle
			(at -27.806904 13.530326)
			(size 0.4318 0.4318)
			(layers "F.Cu" "F.Mask" "F.Paste")
			(net "GND")
		)
		(pad "CW14" smd circle
			(at -26.090118 13.530326)
			(size 0.4318 0.4318)
			(layers "F.Cu" "F.Mask" "F.Paste")
			(net "TP_CPU1_UPI2_RSVD_DF15")
		)
		(pad "CW16" smd circle
			(at -24.373078 13.530326)
			(size 0.4318 0.4318)
			(layers "F.Cu" "F.Mask" "F.Paste")
			(net "TP_CPU1_UPI2_RSVD_DB15")
		)
		(pad "CW18" smd circle
			(at -22.656038 13.530326)
			(size 0.4318 0.4318)
			(layers "F.Cu" "F.Mask" "F.Paste")
			(net "GND")
		)
		(pad "CW20" smd circle
			(at -20.938998 13.530326)
			(size 0.4318 0.4318)
			(layers "F.Cu" "F.Mask" "F.Paste")
			(net "GND")
		)
		(pad "CW22" smd circle
			(at -19.221958 13.530326)
			(size 0.4318 0.4318)
			(layers "F.Cu" "F.Mask" "F.Paste")
			(net "TP_CPU1_KTI2_DFX_DN")
		)
		(pad "CW24" smd circle
			(at -17.504918 13.530326)
			(size 0.4318 0.4318)
			(layers "F.Cu" "F.Mask" "F.Paste")
			(net "PVCCMCP_CPU1")
		)
		(pad "CW26" smd circle
			(at -15.787878 13.530326)
			(size 0.4318 0.4318)
			(layers "F.Cu" "F.Mask" "F.Paste")
			(net "GND")
		)
		(pad "CW28" smd circle
			(at -14.071092 13.530326)
			(size 0.4318 0.4318)
			(layers "F.Cu" "F.Mask" "F.Paste")
			(net "M_M_DQ<62>")
		)
		(pad "CW30" smd circle
			(at -12.354052 13.530326)
			(size 0.4318 0.4318)
			(layers "F.Cu" "F.Mask" "F.Paste")
			(net "M_M_DQ<56>")
		)
		(pad "CW32" smd circle
			(at -10.637012 13.530326)
			(size 0.4318 0.4318)
			(layers "F.Cu" "F.Mask" "F.Paste")
			(net "GND")
		)
		(pad "CW34" smd circle
			(at -8.919972 13.530326)
			(size 0.4318 0.4318)
			(layers "F.Cu" "F.Mask" "F.Paste")
			(net "M_M_DQ<54>")
		)
		(pad "CW36" smd circle
			(at -7.202932 13.530326)
			(size 0.4318 0.4318)
			(layers "F.Cu" "F.Mask" "F.Paste")
			(net "M_M_DQ<48>")
		)
		(pad "CW38" smd circle
			(at -5.485892 13.530326)
			(size 0.4318 0.4318)
			(layers "F.Cu" "F.Mask" "F.Paste")
			(net "GND")
		)
		(pad "CW40" smd circle
			(at -3.769106 13.530326)
			(size 0.4318 0.4318)
			(layers "F.Cu" "F.Mask" "F.Paste")
			(net "GND")
		)
		(pad "CW42" smd circle
			(at -2.052066 13.530326)
			(size 0.4318 0.4318)
			(layers "F.Cu" "F.Mask" "F.Paste")
			(net "GND")
		)
		(pad "CW46" smd circle
			(at 2.910586 11.730228)
			(size 0.508 0.508)
			(layers "F.Cu" "F.Mask" "F.Paste")
			(net "PVCCIN_CPU1")
		)
		(pad "CW48" smd circle
			(at 4.627626 11.730228)
			(size 0.508 0.508)
			(layers "F.Cu" "F.Mask" "F.Paste")
			(net "PVCCIN_CPU1")
		)
		(pad "CW50" smd circle
			(at 6.344412 11.730228)
			(size 0.508 0.508)
			(layers "F.Cu" "F.Mask" "F.Paste")
			(net "PVCCIN_CPU1")
		)
		(pad "CW52" smd circle
			(at 8.061452 11.730228)
			(size 0.4318 0.4318)
			(layers "F.Cu" "F.Mask" "F.Paste")
			(net "GND")
		)
		(pad "CW54" smd circle
			(at 9.778492 11.730228)
			(size 0.4318 0.4318)
			(layers "F.Cu" "F.Mask" "F.Paste")
			(net "GND")
		)
		(pad "CW56" smd circle
			(at 11.495532 11.730228)
			(size 0.4318 0.4318)
			(layers "F.Cu" "F.Mask" "F.Paste")
			(net "PD_PIROM_CPU1_ADDR2")
		)
		(pad "CW58" smd circle
			(at 13.212572 11.730228)
			(size 0.4318 0.4318)
			(layers "F.Cu" "F.Mask" "F.Paste")
			(net "SMB_PIROM_CPU1_SDA")
		)
		(pad "CW60" smd circle
			(at 14.929612 11.730228)
			(size 0.4318 0.4318)
			(layers "F.Cu" "F.Mask" "F.Paste")
			(net "TP_CPU1_RSVD_61")
		)
		(pad "CW62" smd circle
			(at 16.646398 11.730228)
			(size 0.4318 0.4318)
			(layers "F.Cu" "F.Mask" "F.Paste")
			(net "TP_CPU1_RSVD_60")
		)
		(pad "CW64" smd circle
			(at 18.363438 11.730228)
			(size 0.4318 0.4318)
			(layers "F.Cu" "F.Mask" "F.Paste")
			(net "GND")
		)
		(pad "CW66" smd circle
			(at 20.080478 11.730228)
			(size 0.4318 0.4318)
			(layers "F.Cu" "F.Mask" "F.Paste")
			(net "GND")
		)
		(pad "CW68" smd circle
			(at 21.797518 11.730228)
			(size 0.4318 0.4318)
			(layers "F.Cu" "F.Mask" "F.Paste")
			(net "GND")
		)
		(pad "CW72" smd circle
			(at 25.231598 11.730228)
			(size 0.4318 0.4318)
			(layers "F.Cu" "F.Mask" "F.Paste")
			(net "FM_CPU1_PKGID1")
		)
		(pad "CW74" smd circle
			(at 26.948384 11.730228)
			(size 0.4318 0.4318)
			(layers "F.Cu" "F.Mask" "F.Paste")
			(net "GND")
		)
		(pad "CW76" smd circle
			(at 28.665424 11.730228)
			(size 0.4318 0.4318)
			(layers "F.Cu" "F.Mask" "F.Paste")
			(net "M_M_DQ<2>")
		)
		(pad "CW78" smd circle
			(at 30.382464 11.730228)
			(size 0.4318 0.4318)
			(layers "F.Cu" "F.Mask" "F.Paste")
			(net "GND")
		)
		(pad "CW80" smd circle
			(at 32.099504 11.730228)
			(size 0.4318 0.4318)
			(layers "F.Cu" "F.Mask" "F.Paste")
			(net "M_L_DQ<13>")
		)
		(pad "CW82" smd circle
			(at 33.816544 11.730228)
			(size 0.4318 0.4318)
			(layers "F.Cu" "F.Mask" "F.Paste")
			(net "GND")
		)
		(pad "CW84" smd circle
			(at 35.533584 11.730228)
			(size 0.4318 0.4318)
			(layers "F.Cu" "F.Mask" "F.Paste")
			(net "M_K_DQ<7>")
		)
		(pad "CW86" smd custom
			(at 37.250624 11.730228 270)
			(size 0.10795 0.10795)
			(layers "F.Cu" "F.Mask" "F.Paste")
			(net "M_K_DQ<6>")
			(options
				(clearance outline)
				(anchor circle)
			)
			(primitives
				(gr_poly
					(pts
						(arc
							(start 0.2159 -0.0381)
							(mid 0 -0.254)
							(end -0.2159 -0.0381)
						)
						(arc
							(start -0.2159 0.0381)
							(mid 0 0.254)
							(end 0.2159 0.0381)
						)
					)
					(width 0)
					(fill yes)
				)
			)
		)
	)
)
